(kicad_pcb
	(version 20260206)
	(generator "pcbnew")
	(generator_version "10.0")
	(general
		(thickness 1.6)
		(legacy_teardrops no)
	)
	(paper "A4")
	(title_block
		(title "04192023_DAF0TMB3IC0_F0TG_MB_C_brd_V02_OCP.brd")
		(comment 1 "Grand Teton / footprints 8261-8267 of 8354")
	)
	(layers
		(0 "F.Cu" signal "TOP")
		(4 "In1.Cu" signal "GND")
		(6 "In2.Cu" signal "IN1")
		(8 "In3.Cu" signal "GND1")
		(10 "In4.Cu" signal "IN2")
		(12 "In5.Cu" signal "GND2")
		(14 "In6.Cu" signal "IN3")
		(16 "In7.Cu" signal "GND3")
		(18 "In8.Cu" signal "VCC")
		(20 "In9.Cu" signal "VCC1")
		(22 "In10.Cu" signal "GND4")
		(24 "In11.Cu" signal "IN4")
		(26 "In12.Cu" signal "GND5")
		(28 "In13.Cu" signal "IN5")
		(30 "In14.Cu" signal "GND6")
		(32 "In15.Cu" signal "IN6")
		(34 "In16.Cu" signal "GND7")
		(2 "B.Cu" signal "BOTTOM")
		(9 "F.Adhes" user "F.Adhesive")
		(11 "B.Adhes" user "B.Adhesive")
		(13 "F.Paste" user "Package Geometry/Pastemask Top")
		(15 "B.Paste" user "Package Geometry/Pastemask Bottom")
		(5 "F.SilkS" user "Ref Des/Silkscreen Top")
		(7 "B.SilkS" user "Ref Des/Silkscreen Bottom")
		(1 "F.Mask" user "Board Geometry/Soldermask Top")
		(3 "B.Mask" user "Board Geometry/Soldermask Bottom")
		(17 "Dwgs.User" user "User.Drawings")
		(19 "Cmts.User" user "User.Comments")
		(21 "Eco1.User" user "User.Eco1")
		(23 "Eco2.User" user "User.Eco2")
		(25 "Edge.Cuts" user "Board Geometry/Outline")
		(27 "Margin" user)
		(31 "F.CrtYd" user "Package Geometry/Place Bound Top")
		(29 "B.CrtYd" user "Package Geometry/Place Bound Bottom")
		(35 "F.Fab" user "Ref Des/Assembly Top")
		(33 "B.Fab" user "Ref Des/Assembly Bottom")
	)
	(footprint ""
		(layer "B.Cu")
		(at 366.217454 -248.47931 180)
		(property "Reference" "C2169"
			(at 0 0 0)
			(layer "B.SilkS")
			(hide yes)
			(effects
				(font
					(size 1.27 1.27)
				)
				(justify mirror)
			)
		)
		(property "Value" ""
			(at 0 0 0)
			(layer "B.Fab")
			(effects
				(font
					(size 1.27 1.27)
				)
				(justify mirror)
			)
		)
		(duplicate_pad_numbers_are_jumpers no)
		(fp_line
			(start 0.7874 0.4064)
			(end 0.7874 -0.4064)
			(stroke
				(width 0.1524)
				(type default)
			)
			(layer "B.SilkS")
		)
		(fp_line
			(start 0.7874 -0.4064)
			(end -0.7874 -0.4064)
			(stroke
				(width 0.1524)
				(type default)
			)
			(layer "B.SilkS")
		)
		(fp_line
			(start -0.7874 0.4064)
			(end 0.7874 0.4064)
			(stroke
				(width 0.1524)
				(type default)
			)
			(layer "B.SilkS")
		)
		(fp_line
			(start -0.7874 -0.4064)
			(end -0.7874 0.4064)
			(stroke
				(width 0.1524)
				(type default)
			)
			(layer "B.SilkS")
		)
		(fp_line
			(start 0.67945 0.3048)
			(end 0.67945 -0.305054)
			(stroke
				(width 0.1)
				(type default)
			)
			(layer "B.Fab")
		)
		(fp_line
			(start 0.67945 -0.305054)
			(end 0.12065 -0.305054)
			(stroke
				(width 0.1)
				(type default)
			)
			(layer "B.Fab")
		)
		(fp_line
			(start 0.12065 0.3048)
			(end 0.67945 0.3048)
			(stroke
				(width 0.1)
				(type default)
			)
			(layer "B.Fab")
		)
		(fp_line
			(start 0.12065 0.2794)
			(end 0.12065 0.3048)
			(stroke
				(width 0.1)
				(type default)
			)
			(layer "B.Fab")
		)
		(fp_line
			(start 0.12065 -0.2794)
			(end -0.12065 -0.2794)
			(stroke
				(width 0.1)
				(type default)
			)
			(layer "B.Fab")
		)
		(fp_line
			(start 0.12065 -0.305054)
			(end 0.12065 -0.2794)
			(stroke
				(width 0.1)
				(type default)
			)
			(layer "B.Fab")
		)
		(fp_line
			(start -0.120396 0.3048)
			(end -0.120396 0.2794)
			(stroke
				(width 0.1)
				(type default)
			)
			(layer "B.Fab")
		)
		(fp_line
			(start -0.120396 0.2794)
			(end 0.12065 0.2794)
			(stroke
				(width 0.1)
				(type default)
			)
			(layer "B.Fab")
		)
		(fp_line
			(start -0.12065 -0.2794)
			(end -0.12065 -0.3048)
			(stroke
				(width 0.1)
				(type default)
			)
			(layer "B.Fab")
		)
		(fp_line
			(start -0.12065 -0.3048)
			(end -0.67945 -0.3048)
			(stroke
				(width 0.1)
				(type default)
			)
			(layer "B.Fab")
		)
		(fp_line
			(start -0.67945 0.3048)
			(end -0.120396 0.3048)
			(stroke
				(width 0.1)
				(type default)
			)
			(layer "B.Fab")
		)
		(fp_line
			(start -0.67945 -0.3048)
			(end -0.67945 0.3048)
			(stroke
				(width 0.1)
				(type default)
			)
			(layer "B.Fab")
		)
		(pad "1" smd circle
			(at 0.40005 0)
			(size 0 0)
			(layers "B.Cu" "B.Mask" "B.Paste")
			(net "PVDDCR_CPU0_P0")
		)
		(pad "2" smd circle
			(at -0.40005 0)
			(size 0 0)
			(layers "B.Cu" "B.Mask" "B.Paste")
			(net "GND")
		)
	)
	(footprint ""
		(layer "B.Cu")
		(at 181.737 -100.294948 90)
		(property "Reference" "R226"
			(at 0 0 90)
			(layer "B.SilkS")
			(hide yes)
			(effects
				(font
					(size 1.27 1.27)
				)
				(justify mirror)
			)
		)
		(property "Value" ""
			(at 0 0 90)
			(layer "B.Fab")
			(effects
				(font
					(size 1.27 1.27)
				)
				(justify mirror)
			)
		)
		(duplicate_pad_numbers_are_jumpers no)
		(fp_line
			(start 0.7874 -0.4064)
			(end -0.7874 -0.4064)
			(stroke
				(width 0.1524)
				(type default)
			)
			(layer "B.SilkS")
		)
		(fp_line
			(start -0.7874 -0.4064)
			(end -0.7874 0.4064)
			(stroke
				(width 0.1524)
				(type default)
			)
			(layer "B.SilkS")
		)
		(fp_line
			(start 0.7874 0.4064)
			(end 0.7874 -0.4064)
			(stroke
				(width 0.1524)
				(type default)
			)
			(layer "B.SilkS")
		)
		(fp_line
			(start -0.7874 0.4064)
			(end 0.7874 0.4064)
			(stroke
				(width 0.1524)
				(type default)
			)
			(layer "B.SilkS")
		)
		(fp_line
			(start 0.67945 -0.305054)
			(end 0.12065 -0.305054)
			(stroke
				(width 0.1)
				(type default)
			)
			(layer "B.Fab")
		)
		(fp_line
			(start 0.12065 -0.305054)
			(end 0.12065 -0.2794)
			(stroke
				(width 0.1)
				(type default)
			)
			(layer "B.Fab")
		)
		(fp_line
			(start -0.12065 -0.3048)
			(end -0.67945 -0.3048)
			(stroke
				(width 0.1)
				(type default)
			)
			(layer "B.Fab")
		)
		(fp_line
			(start -0.67945 -0.3048)
			(end -0.67945 0.3048)
			(stroke
				(width 0.1)
				(type default)
			)
			(layer "B.Fab")
		)
		(fp_line
			(start 0.12065 -0.2794)
			(end -0.12065 -0.2794)
			(stroke
				(width 0.1)
				(type default)
			)
			(layer "B.Fab")
		)
		(fp_line
			(start -0.12065 -0.2794)
			(end -0.12065 -0.3048)
			(stroke
				(width 0.1)
				(type default)
			)
			(layer "B.Fab")
		)
		(fp_line
			(start 0.12065 0.2794)
			(end 0.12065 0.3048)
			(stroke
				(width 0.1)
				(type default)
			)
			(layer "B.Fab")
		)
		(fp_line
			(start -0.120396 0.2794)
			(end 0.12065 0.2794)
			(stroke
				(width 0.1)
				(type default)
			)
			(layer "B.Fab")
		)
		(fp_line
			(start 0.67945 0.3048)
			(end 0.67945 -0.305054)
			(stroke
				(width 0.1)
				(type default)
			)
			(layer "B.Fab")
		)
		(fp_line
			(start 0.12065 0.3048)
			(end 0.67945 0.3048)
			(stroke
				(width 0.1)
				(type default)
			)
			(layer "B.Fab")
		)
		(fp_line
			(start -0.120396 0.3048)
			(end -0.120396 0.2794)
			(stroke
				(width 0.1)
				(type default)
			)
			(layer "B.Fab")
		)
		(fp_line
			(start -0.67945 0.3048)
			(end -0.120396 0.3048)
			(stroke
				(width 0.1)
				(type default)
			)
			(layer "B.Fab")
		)
		(pad "1" smd circle
			(at 0.40005 0 270)
			(size 0 0)
			(layers "B.Cu" "B.Mask" "B.Paste")
			(net "FM_PVDD11_S3_P0_OCP_N")
		)
		(pad "2" smd circle
			(at -0.40005 0 270)
			(size 0 0)
			(layers "B.Cu" "B.Mask" "B.Paste")
			(net "PVDD11_S3_P0_OCP_N")
		)
	)
	(footprint ""
		(layer "B.Cu")
		(at 397.623538 -392.1252 180)
		(property "Reference" "R1063"
			(at 0 0 0)
			(layer "B.SilkS")
			(hide yes)
			(effects
				(font
					(size 1.27 1.27)
				)
				(justify mirror)
			)
		)
		(property "Value" ""
			(at 0 0 0)
			(layer "B.Fab")
			(effects
				(font
					(size 1.27 1.27)
				)
				(justify mirror)
			)
		)
		(duplicate_pad_numbers_are_jumpers no)
		(fp_line
			(start 0.32512 0.175006)
			(end 0.32512 -0.175006)
			(stroke
				(width 0.1)
				(type default)
			)
			(layer "B.Fab")
		)
		(fp_line
			(start 0.32512 -0.175006)
			(end -0.32512 -0.175006)
			(stroke
				(width 0.1)
				(type default)
			)
			(layer "B.Fab")
		)
		(fp_line
			(start -0.32512 0.175006)
			(end 0.32512 0.175006)
			(stroke
				(width 0.1)
				(type default)
			)
			(layer "B.Fab")
		)
		(fp_line
			(start -0.32512 -0.175006)
			(end -0.32512 0.175006)
			(stroke
				(width 0.1)
				(type default)
			)
			(layer "B.Fab")
		)
		(pad "1" smd rect
			(at 0.2667 0)
			(size 0.3048 0.381)
			(layers "B.Cu" "B.Mask" "B.Paste")
			(net "P1V8_CPU0_RT_1D")
		)
		(pad "2" smd rect
			(at -0.2667 0 180)
			(size 0.3048 0.381)
			(layers "B.Cu" "B.Mask" "B.Paste")
			(net "RT_CPU0_P2_SCAN_MODE")
		)
	)
	(footprint ""
		(layer "B.Cu")
		(at 199.129396 -116.174012 -90)
		(property "Reference" "R6048"
			(at 0 0 90)
			(layer "B.SilkS")
			(hide yes)
			(effects
				(font
					(size 1.27 1.27)
				)
				(justify mirror)
			)
		)
		(property "Value" ""
			(at 0 0 90)
			(layer "B.Fab")
			(effects
				(font
					(size 1.27 1.27)
				)
				(justify mirror)
			)
		)
		(duplicate_pad_numbers_are_jumpers no)
		(fp_line
			(start -0.7874 0.4064)
			(end 0.7874 0.4064)
			(stroke
				(width 0.1524)
				(type default)
			)
			(layer "B.SilkS")
		)
		(fp_line
			(start 0.7874 0.4064)
			(end 0.7874 -0.4064)
			(stroke
				(width 0.1524)
				(type default)
			)
			(layer "B.SilkS")
		)
		(fp_line
			(start -0.7874 -0.4064)
			(end -0.7874 0.4064)
			(stroke
				(width 0.1524)
				(type default)
			)
			(layer "B.SilkS")
		)
		(fp_line
			(start 0.7874 -0.4064)
			(end -0.7874 -0.4064)
			(stroke
				(width 0.1524)
				(type default)
			)
			(layer "B.SilkS")
		)
		(fp_line
			(start -0.67945 0.3048)
			(end -0.120396 0.3048)
			(stroke
				(width 0.1)
				(type default)
			)
			(layer "B.Fab")
		)
		(fp_line
			(start -0.120396 0.3048)
			(end -0.120396 0.2794)
			(stroke
				(width 0.1)
				(type default)
			)
			(layer "B.Fab")
		)
		(fp_line
			(start 0.12065 0.3048)
			(end 0.67945 0.3048)
			(stroke
				(width 0.1)
				(type default)
			)
			(layer "B.Fab")
		)
		(fp_line
			(start 0.67945 0.3048)
			(end 0.67945 -0.305054)
			(stroke
				(width 0.1)
				(type default)
			)
			(layer "B.Fab")
		)
		(fp_line
			(start -0.120396 0.2794)
			(end 0.12065 0.2794)
			(stroke
				(width 0.1)
				(type default)
			)
			(layer "B.Fab")
		)
		(fp_line
			(start 0.12065 0.2794)
			(end 0.12065 0.3048)
			(stroke
				(width 0.1)
				(type default)
			)
			(layer "B.Fab")
		)
		(fp_line
			(start -0.12065 -0.2794)
			(end -0.12065 -0.3048)
			(stroke
				(width 0.1)
				(type default)
			)
			(layer "B.Fab")
		)
		(fp_line
			(start 0.12065 -0.2794)
			(end -0.12065 -0.2794)
			(stroke
				(width 0.1)
				(type default)
			)
			(layer "B.Fab")
		)
		(fp_line
			(start -0.67945 -0.3048)
			(end -0.67945 0.3048)
			(stroke
				(width 0.1)
				(type default)
			)
			(layer "B.Fab")
		)
		(fp_line
			(start -0.12065 -0.3048)
			(end -0.67945 -0.3048)
			(stroke
				(width 0.1)
				(type default)
			)
			(layer "B.Fab")
		)
		(fp_line
			(start 0.12065 -0.305054)
			(end 0.12065 -0.2794)
			(stroke
				(width 0.1)
				(type default)
			)
			(layer "B.Fab")
		)
		(fp_line
			(start 0.67945 -0.305054)
			(end 0.12065 -0.305054)
			(stroke
				(width 0.1)
				(type default)
			)
			(layer "B.Fab")
		)
		(pad "1" smd circle
			(at 0.40005 0 90)
			(size 0 0)
			(layers "B.Cu" "B.Mask" "B.Paste")
			(net "HP_LVC3_E1S_0_HSC_PWRGD")
		)
		(pad "2" smd circle
			(at -0.40005 0 90)
			(size 0 0)
			(layers "B.Cu" "B.Mask" "B.Paste")
			(net "P12V_E1S_0_PWRGD")
		)
	)
	(footprint ""
		(layer "B.Cu")
		(at 183.616346 -192.66027)
		(property "Reference" "C535"
			(at 0 0 0)
			(layer "B.SilkS")
			(hide yes)
			(effects
				(font
					(size 1.27 1.27)
				)
				(justify mirror)
			)
		)
		(property "Value" ""
			(at 0 0 0)
			(layer "B.Fab")
			(effects
				(font
					(size 1.27 1.27)
				)
				(justify mirror)
			)
		)
		(duplicate_pad_numbers_are_jumpers no)
		(fp_line
			(start -1.524 -0.762)
			(end -1.524 0.762)
			(stroke
				(width 0.1524)
				(type default)
			)
			(layer "B.SilkS")
		)
		(fp_line
			(start -1.524 0.762)
			(end 1.524 0.762)
			(stroke
				(width 0.1524)
				(type default)
			)
			(layer "B.SilkS")
		)
		(fp_line
			(start 1.524 -0.762)
			(end -1.524 -0.762)
			(stroke
				(width 0.1524)
				(type default)
			)
			(layer "B.SilkS")
		)
		(fp_line
			(start 1.524 0.762)
			(end 1.524 -0.762)
			(stroke
				(width 0.1524)
				(type default)
			)
			(layer "B.SilkS")
		)
		(fp_line
			(start -1.1049 -0.724916)
			(end 1.1049 -0.724916)
			(stroke
				(width 0.1)
				(type default)
			)
			(layer "B.Fab")
		)
		(fp_line
			(start -1.1049 0.724916)
			(end -1.1049 -0.724916)
			(stroke
				(width 0.1)
				(type default)
			)
			(layer "B.Fab")
		)
		(fp_line
			(start 1.1049 -0.724916)
			(end 1.1049 0.724916)
			(stroke
				(width 0.1)
				(type default)
			)
			(layer "B.Fab")
		)
		(fp_line
			(start 1.1049 0.724916)
			(end -1.1049 0.724916)
			(stroke
				(width 0.1)
				(type default)
			)
			(layer "B.Fab")
		)
		(pad "1" smd rect
			(at 0.889 0)
			(size 1.016 1.27)
			(layers "B.Cu" "B.Mask" "B.Paste")
			(net "P12V_MEM_CPU1")
		)
		(pad "2" smd rect
			(at -0.889 0)
			(size 1.016 1.27)
			(layers "B.Cu" "B.Mask" "B.Paste")
			(net "GND")
		)
	)
	(footprint ""
		(layer "B.Cu")
		(at 374.218454 -396.393162 -90)
		(property "Reference" "C1035"
			(at 0 0 90)
			(layer "B.SilkS")
			(hide yes)
			(effects
				(font
					(size 1.27 1.27)
				)
				(justify mirror)
			)
		)
		(property "Value" ""
			(at 0 0 90)
			(layer "B.Fab")
			(effects
				(font
					(size 1.27 1.27)
				)
				(justify mirror)
			)
		)
		(duplicate_pad_numbers_are_jumpers no)
		(fp_line
			(start -0.299974 0.150114)
			(end 0.299974 0.150114)
			(stroke
				(width 0.1)
				(type default)
			)
			(layer "B.Fab")
		)
		(fp_line
			(start 0.299974 0.150114)
			(end 0.299974 -0.150114)
			(stroke
				(width 0.1)
				(type default)
			)
			(layer "B.Fab")
		)
		(fp_line
			(start -0.299974 -0.150114)
			(end -0.299974 0.150114)
			(stroke
				(width 0.1)
				(type default)
			)
			(layer "B.Fab")
		)
		(fp_line
			(start 0.299974 -0.150114)
			(end -0.299974 -0.150114)
			(stroke
				(width 0.1)
				(type default)
			)
			(layer "B.Fab")
		)
		(pad "1" smd rect
			(at 0.2667 0 90)
			(size 0.3048 0.381)
			(layers "B.Cu" "B.Mask" "B.Paste")
			(net "P0V9_CPU0_RT3_2A")
		)
		(pad "2" smd rect
			(at -0.2667 0 90)
			(size 0.3048 0.381)
			(layers "B.Cu" "B.Mask" "B.Paste")
			(net "GND")
		)
	)
	(footprint ""
		(layer "B.Cu")
		(at 144.922494 -313.45505 180)
		(property "Reference" "R536"
			(at 0 0 0)
			(layer "B.SilkS")
			(hide yes)
			(effects
				(font
					(size 1.27 1.27)
				)
				(justify mirror)
			)
		)
		(property "Value" ""
			(at 0 0 0)
			(layer "B.Fab")
			(effects
				(font
					(size 1.27 1.27)
				)
				(justify mirror)
			)
		)
		(duplicate_pad_numbers_are_jumpers no)
		(fp_line
			(start 0.7874 0.4064)
			(end 0.7874 -0.4064)
			(stroke
				(width 0.1524)
				(type default)
			)
			(layer "B.SilkS")
		)
		(fp_line
			(start 0.7874 -0.4064)
			(end -0.7874 -0.4064)
			(stroke
				(width 0.1524)
				(type default)
			)
			(layer "B.SilkS")
		)
		(fp_line
			(start -0.7874 0.4064)
			(end 0.7874 0.4064)
			(stroke
				(width 0.1524)
				(type default)
			)
			(layer "B.SilkS")
		)
		(fp_line
			(start -0.7874 -0.4064)
			(end -0.7874 0.4064)
			(stroke
				(width 0.1524)
				(type default)
			)
			(layer "B.SilkS")
		)
		(fp_line
			(start 0.67945 0.3048)
			(end 0.67945 -0.305054)
			(stroke
				(width 0.1)
				(type default)
			)
			(layer "B.Fab")
		)
		(fp_line
			(start 0.67945 -0.305054)
			(end 0.12065 -0.305054)
			(stroke
				(width 0.1)
				(type default)
			)
			(layer "B.Fab")
		)
		(fp_line
			(start 0.12065 0.3048)
			(end 0.67945 0.3048)
			(stroke
				(width 0.1)
				(type default)
			)
			(layer "B.Fab")
		)
		(fp_line
			(start 0.12065 0.2794)
			(end 0.12065 0.3048)
			(stroke
				(width 0.1)
				(type default)
			)
			(layer "B.Fab")
		)
		(fp_line
			(start 0.12065 -0.2794)
			(end -0.12065 -0.2794)
			(stroke
				(width 0.1)
				(type default)
			)
			(layer "B.Fab")
		)
		(fp_line
			(start 0.12065 -0.305054)
			(end 0.12065 -0.2794)
			(stroke
				(width 0.1)
				(type default)
			)
			(layer "B.Fab")
		)
		(fp_line
			(start -0.120396 0.3048)
			(end -0.120396 0.2794)
			(stroke
				(width 0.1)
				(type default)
			)
			(layer "B.Fab")
		)
		(fp_line
			(start -0.120396 0.2794)
			(end 0.12065 0.2794)
			(stroke
				(width 0.1)
				(type default)
			)
			(layer "B.Fab")
		)
		(fp_line
			(start -0.12065 -0.2794)
			(end -0.12065 -0.3048)
			(stroke
				(width 0.1)
				(type default)
			)
			(layer "B.Fab")
		)
		(fp_line
			(start -0.12065 -0.3048)
			(end -0.67945 -0.3048)
			(stroke
				(width 0.1)
				(type default)
			)
			(layer "B.Fab")
		)
		(fp_line
			(start -0.67945 0.3048)
			(end -0.120396 0.3048)
			(stroke
				(width 0.1)
				(type default)
			)
			(layer "B.Fab")
		)
		(fp_line
			(start -0.67945 -0.3048)
			(end -0.67945 0.3048)
			(stroke
				(width 0.1)
				(type default)
			)
			(layer "B.Fab")
		)
		(pad "1" smd circle
			(at 0.40005 0)
			(size 0 0)
			(layers "B.Cu" "B.Mask" "B.Paste")
			(net "CPU1_THERMTRIP_N")
		)
		(pad "2" smd circle
			(at -0.40005 0)
			(size 0 0)
			(layers "B.Cu" "B.Mask" "B.Paste")
			(net "PVDD18_S5_P1")
		)
	)
)
